(kicad_pcb
	(version 20241229)
	(generator "pcbnew")
	(generator_version "9.0")
	(general
		(thickness 1.294)
		(legacy_teardrops no)
	)
	(paper "A3")
	(title_block
		(title "Kintex 410T devboard")
		(date "2024-04-03")
		(rev "1.1.2")
		(comment 9 "footprints 288-288 of 975")
	)
	(layers
		(0 "F.Cu" mixed)
		(4 "In1.Cu" power)
		(6 "In2.Cu" power)
		(8 "In3.Cu" mixed)
		(10 "In4.Cu" power)
		(12 "In5.Cu" mixed)
		(14 "In6.Cu" power)
		(16 "In7.Cu" mixed)
		(18 "In8.Cu" power)
		(2 "B.Cu" mixed)
		(9 "F.Adhes" user "F.Adhesive")
		(11 "B.Adhes" user "B.Adhesive")
		(13 "F.Paste" user)
		(15 "B.Paste" user)
		(5 "F.SilkS" user "F.Silkscreen")
		(7 "B.SilkS" user "B.Silkscreen")
		(1 "F.Mask" user)
		(3 "B.Mask" user)
		(17 "Dwgs.User" user "User.Drawings")
		(19 "Cmts.User" user "User.Comments")
		(21 "Eco1.User" user "User.Eco1")
		(23 "Eco2.User" user "User.Eco2")
		(25 "Edge.Cuts" user)
		(27 "Margin" user)
		(31 "F.CrtYd" user "F.Courtyard")
		(29 "B.CrtYd" user "B.Courtyard")
		(35 "F.Fab" user)
		(33 "B.Fab" user)
	)
	(footprint "antmicro-footprints:R_0402_1005Metric"
		(layer "F.Cu")
		(at 164.0625 168.6 90)
		(descr "Resistor SMD 0402")
		(tags "resistor SMD 0402")
		(property "Reference" "R298"
			(at -1 1.2375 90)
			(layer "F.SilkS")
			(effects
				(font
					(size 0.7 0.7)
					(thickness 0.15)
				)
				(justify left bottom)
			)
		)
		(property "Value" "R_0R_0402"
			(at 0 1.4 90)
			(layer "F.Fab")
			(effects
				(font
					(size 0.7 0.7)
					(thickness 0.15)
				)
				(justify left bottom)
			)
		)
		(property "Description" "SMD Chip Resistor, Jumper, 0 ohm, 100 mW, 0402 [1005 Metric], Thick Film, General Purpose"
			(at 0 0 90)
			(layer "F.Fab")
			(hide yes)
			(effects
				(font
					(size 1.27 1.27)
					(thickness 0.15)
				)
			)
		)
		(property "Author" "Antmicro"
			(at 332.6625 4.5375 0)
			(layer "F.Fab")
			(hide yes)
			(effects
				(font
					(size 1 1)
					(thickness 0.15)
				)
			)
		)
		(property "Current" "1A"
			(at 332.6625 4.5375 0)
			(layer "F.Fab")
			(hide yes)
			(effects
				(font
					(size 1 1)
					(thickness 0.15)
				)
			)
		)
		(property "License" "Apache-2.0"
			(at 332.6625 4.5375 0)
			(layer "F.Fab")
			(hide yes)
			(effects
				(font
					(size 1 1)
					(thickness 0.15)
				)
			)
		)
		(property "MPN" "ERJ2GE0R00X"
			(at 332.6625 4.5375 0)
			(layer "F.Fab")
			(hide yes)
			(effects
				(font
					(size 1 1)
					(thickness 0.15)
				)
			)
		)
		(property "Manufacturer" "Panasonic"
			(at 332.6625 4.5375 0)
			(layer "F.Fab")
			(hide yes)
			(effects
				(font
					(size 1 1)
					(thickness 0.15)
				)
			)
		)
		(property "Tolerance" ""
			(at 332.6625 4.5375 0)
			(layer "F.Fab")
			(hide yes)
			(effects
				(font
					(size 1 1)
					(thickness 0.15)
				)
			)
		)
		(property "Val" "0R"
			(at 332.6625 4.5375 0)
			(layer "F.Fab")
			(hide yes)
			(effects
				(font
					(size 1 1)
					(thickness 0.15)
				)
			)
		)
		(sheetname "DC-DC Converters")
		(sheetfile "dc-dc.kicad_sch")
		(attr smd)
		(fp_rect
			(start -0.925 -0.47)
			(end 0.925 0.47)
			(stroke
				(width 0.05)
				(type default)
			)
			(fill no)
			(layer "F.CrtYd")
		)
		(fp_rect
			(start -0.5 -0.25)
			(end 0.5 0.25)
			(stroke
				(width 0.15)
				(type solid)
			)
			(fill no)
			(layer "F.Fab")
		)
		(pad "1" smd roundrect
			(at -0.48 0 90)
			(size 0.59 0.64)
			(layers "F.Cu" "F.Mask" "F.Paste")
			(roundrect_rratio 0.25)
			(net 960 "/DC-DC Converters/FB2")
			(pintype "passive")
		)
		(pad "2" smd roundrect
			(at 0.48 0 90)
			(size 0.59 0.64)
			(layers "F.Cu" "F.Mask" "F.Paste")
			(roundrect_rratio 0.25)
			(net 734 "/DC-DC Converters/1V8_local")
			(pintype "passive")
		)
	)
)
